# S9S_MB_2U (Grand Teton) — schematic netlist excerpt (pin names and nets, part order shuffled) for the footprints in the layout excerpt that follows; sources: Cadence DE-HDL packaged netlist, KiCad conversion of 03242023_DA0F0TMBIJ0_F0T_Motherboard_J_brd_V01_OCP.brd

R4096  Q_RES  10K 1% CHIP  pkg 0402LF  page 183 : A = PD_PCH_GPPC_A_18 ; B = GND
PC1230  Q_CAPP  560UF 2.5V 20% OSCON  pkg THLF  page 262 : A = P1V05_PCH_AUX ; B = GND
R4590  Q_RES  1K 1% EMPTY  pkg 0402LF  page 195 : A = FAB_BMC_REV_ID1 ; B = GND

(kicad_pcb
	(version 20260206)
	(generator "pcbnew")
	(generator_version "10.0")
	(general
		(thickness 1.6)
		(legacy_teardrops no)
	)
	(paper "A4")
	(title_block
		(title "03242023_DA0F0TMBIJ0_F0T_Motherboard_J_brd_V01_OCP.brd")
		(comment 1 "Grand Teton / footprints 3199-3201 of 6105")
	)
	(layers
		(0 "F.Cu" signal "TOP")
		(4 "In1.Cu" signal "GND")
		(6 "In2.Cu" signal "IN1")
		(8 "In3.Cu" signal "GND1")
		(10 "In4.Cu" signal "IN2")
		(12 "In5.Cu" signal "GND2")
		(14 "In6.Cu" signal "IN3")
		(16 "In7.Cu" signal "GND3")
		(18 "In8.Cu" signal "VCC")
		(20 "In9.Cu" signal "VCC1")
		(22 "In10.Cu" signal "GND4")
		(24 "In11.Cu" signal "IN4")
		(26 "In12.Cu" signal "GND5")
		(28 "In13.Cu" signal "IN5")
		(30 "In14.Cu" signal "GND6")
		(32 "In15.Cu" signal "IN6")
		(34 "In16.Cu" signal "GND7")
		(2 "B.Cu" signal "BOTTOM")
		(9 "F.Adhes" user "F.Adhesive")
		(11 "B.Adhes" user "B.Adhesive")
		(13 "F.Paste" user "Package Geometry/Pastemask Top")
		(15 "B.Paste" user "Package Geometry/Pastemask Bottom")
		(5 "F.SilkS" user "Ref Des/Silkscreen Top")
		(7 "B.SilkS" user "Ref Des/Silkscreen Bottom")
		(1 "F.Mask" user "Board Geometry/Soldermask Top")
		(3 "B.Mask" user "Board Geometry/Soldermask Bottom")
		(17 "Dwgs.User" user "User.Drawings")
		(19 "Cmts.User" user "User.Comments")
		(21 "Eco1.User" user "User.Eco1")
		(23 "Eco2.User" user "User.Eco2")
		(25 "Edge.Cuts" user "Board Geometry/Outline")
		(27 "Margin" user)
		(31 "F.CrtYd" user "Package Geometry/Place Bound Top")
		(29 "B.CrtYd" user "Package Geometry/Place Bound Bottom")
		(35 "F.Fab" user "Ref Des/Assembly Top")
		(33 "B.Fab" user "Ref Des/Assembly Bottom")
	)
	(footprint ""
		(layer "F.Cu")
		(at 279.5778 -72.050148)
		(property "Reference" "PC1230"
			(at 0 0 0)
			(layer "F.SilkS")
			(hide yes)
			(effects
				(font
					(size 1.27 1.27)
				)
			)
		)
		(property "Value" ""
			(at 0 0 0)
			(layer "F.Fab")
			(effects
				(font
					(size 1.27 1.27)
				)
			)
		)
		(duplicate_pad_numbers_are_jumpers no)
		(fp_line
			(start 2.750058 0.999998)
			(end -2.750058 0.999998)
			(stroke
				(width 0.1524)
				(type default)
			)
			(layer "F.SilkS")
		)
		(fp_circle
			(center 0 0.999998)
			(end 2.750058 0.999998)
			(stroke
				(width 0.1524)
				(type default)
			)
			(fill no)
			(layer "F.SilkS")
		)
		(fp_poly
			(pts
				(arc
					(start 2.750058 0.999998)
					(mid 0 3.750056)
					(end -2.750058 0.999998)
				)
			)
			(stroke
				(width 0)
				(type default)
			)
			(fill yes)
			(layer "F.SilkS")
		)
		(fp_circle
			(center 0 0.999998)
			(end 2.750058 0.999998)
			(stroke
				(width 0.1)
				(type default)
			)
			(fill no)
			(layer "F.Fab")
		)
		(pad "1" thru_hole rect
			(at 0 0)
			(size 1.5748 1.5748)
			(drill 1.0668)
			(layers "*.Cu" "*.Mask")
			(remove_unused_layers no)
			(net "P1V05_PCH_AUX")
			(clearance 0)
			(padstack
				(mode front_inner_back)
				(layer "Inner"
					(shape circle)
					(size 1.5748 1.5748)
					(clearance 0)
				)
				(layer "B.Cu"
					(shape rect)
					(size 1.5748 1.5748)
					(clearance 0)
				)
			)
		)
		(pad "2" thru_hole circle
			(at 0 1.999996)
			(size 1.5748 1.5748)
			(drill 1.0668)
			(layers "*.Cu" "*.Mask")
			(remove_unused_layers no)
			(net "GND")
			(clearance 0)
		)
	)
	(footprint ""
		(layer "F.Cu")
		(at 181.7624 -94.338648 90)
		(property "Reference" "R4590"
			(at 0 0 90)
			(layer "F.SilkS")
			(hide yes)
			(effects
				(font
					(size 1.27 1.27)
				)
			)
		)
		(property "Value" ""
			(at 0 0 90)
			(layer "F.Fab")
			(effects
				(font
					(size 1.27 1.27)
				)
			)
		)
		(duplicate_pad_numbers_are_jumpers no)
		(fp_line
			(start 0.7874 -0.4064)
			(end 0.7874 0.4064)
			(stroke
				(width 0.1524)
				(type default)
			)
			(layer "F.SilkS")
		)
		(fp_line
			(start -0.7874 -0.4064)
			(end 0.7874 -0.4064)
			(stroke
				(width 0.1524)
				(type default)
			)
			(layer "F.SilkS")
		)
		(fp_line
			(start 0.7874 0.4064)
			(end -0.7874 0.4064)
			(stroke
				(width 0.1524)
				(type default)
			)
			(layer "F.SilkS")
		)
		(fp_line
			(start -0.7874 0.4064)
			(end -0.7874 -0.4064)
			(stroke
				(width 0.1524)
				(type default)
			)
			(layer "F.SilkS")
		)
		(fp_line
			(start -0.12065 -0.305054)
			(end -0.12065 -0.2794)
			(stroke
				(width 0.1)
				(type default)
			)
			(layer "F.Fab")
		)
		(fp_line
			(start -0.67945 -0.305054)
			(end -0.12065 -0.305054)
			(stroke
				(width 0.1)
				(type default)
			)
			(layer "F.Fab")
		)
		(fp_line
			(start 0.67945 -0.3048)
			(end 0.67945 0.3048)
			(stroke
				(width 0.1)
				(type default)
			)
			(layer "F.Fab")
		)
		(fp_line
			(start 0.12065 -0.3048)
			(end 0.67945 -0.3048)
			(stroke
				(width 0.1)
				(type default)
			)
			(layer "F.Fab")
		)
		(fp_line
			(start 0.12065 -0.2794)
			(end 0.12065 -0.3048)
			(stroke
				(width 0.1)
				(type default)
			)
			(layer "F.Fab")
		)
		(fp_line
			(start -0.12065 -0.2794)
			(end 0.12065 -0.2794)
			(stroke
				(width 0.1)
				(type default)
			)
			(layer "F.Fab")
		)
		(fp_line
			(start 0.120396 0.2794)
			(end -0.12065 0.2794)
			(stroke
				(width 0.1)
				(type default)
			)
			(layer "F.Fab")
		)
		(fp_line
			(start -0.12065 0.2794)
			(end -0.12065 0.3048)
			(stroke
				(width 0.1)
				(type default)
			)
			(layer "F.Fab")
		)
		(fp_line
			(start 0.67945 0.3048)
			(end 0.120396 0.3048)
			(stroke
				(width 0.1)
				(type default)
			)
			(layer "F.Fab")
		)
		(fp_line
			(start 0.120396 0.3048)
			(end 0.120396 0.2794)
			(stroke
				(width 0.1)
				(type default)
			)
			(layer "F.Fab")
		)
		(fp_line
			(start -0.12065 0.3048)
			(end -0.67945 0.3048)
			(stroke
				(width 0.1)
				(type default)
			)
			(layer "F.Fab")
		)
		(fp_line
			(start -0.67945 0.3048)
			(end -0.67945 -0.305054)
			(stroke
				(width 0.1)
				(type default)
			)
			(layer "F.Fab")
		)
		(pad "1" smd rect
			(at -0.40005 0 270)
			(size 0.4572 0.508)
			(layers "F.Cu" "F.Mask" "F.Paste")
			(net "FAB_BMC_REV_ID1")
		)
		(pad "2" smd rect
			(at 0.40005 0 270)
			(size 0.4572 0.508)
			(layers "F.Cu" "F.Mask" "F.Paste")
			(net "GND")
		)
	)
	(footprint ""
		(layer "F.Cu")
		(at 327.129902 -22.661626 -90)
		(property "Reference" "R4096"
			(at 0 0 270)
			(layer "F.SilkS")
			(hide yes)
			(effects
				(font
					(size 1.27 1.27)
				)
			)
		)
		(property "Value" ""
			(at 0 0 270)
			(layer "F.Fab")
			(effects
				(font
					(size 1.27 1.27)
				)
			)
		)
		(duplicate_pad_numbers_are_jumpers no)
		(fp_line
			(start -0.7874 0.4064)
			(end -0.7874 -0.4064)
			(stroke
				(width 0.1524)
				(type default)
			)
			(layer "F.SilkS")
		)
		(fp_line
			(start 0.7874 0.4064)
			(end -0.7874 0.4064)
			(stroke
				(width 0.1524)
				(type default)
			)
			(layer "F.SilkS")
		)
		(fp_line
			(start -0.7874 -0.4064)
			(end 0.7874 -0.4064)
			(stroke
				(width 0.1524)
				(type default)
			)
			(layer "F.SilkS")
		)
		(fp_line
			(start 0.7874 -0.4064)
			(end 0.7874 0.4064)
			(stroke
				(width 0.1524)
				(type default)
			)
			(layer "F.SilkS")
		)
		(fp_line
			(start -0.67945 0.3048)
			(end -0.67945 -0.305054)
			(stroke
				(width 0.1)
				(type default)
			)
			(layer "F.Fab")
		)
		(fp_line
			(start -0.12065 0.3048)
			(end -0.67945 0.3048)
			(stroke
				(width 0.1)
				(type default)
			)
			(layer "F.Fab")
		)
		(fp_line
			(start 0.120396 0.3048)
			(end 0.120396 0.2794)
			(stroke
				(width 0.1)
				(type default)
			)
			(layer "F.Fab")
		)
		(fp_line
			(start 0.67945 0.3048)
			(end 0.120396 0.3048)
			(stroke
				(width 0.1)
				(type default)
			)
			(layer "F.Fab")
		)
		(fp_line
			(start -0.12065 0.2794)
			(end -0.12065 0.3048)
			(stroke
				(width 0.1)
				(type default)
			)
			(layer "F.Fab")
		)
		(fp_line
			(start 0.120396 0.2794)
			(end -0.12065 0.2794)
			(stroke
				(width 0.1)
				(type default)
			)
			(layer "F.Fab")
		)
		(fp_line
			(start -0.12065 -0.2794)
			(end 0.12065 -0.2794)
			(stroke
				(width 0.1)
				(type default)
			)
			(layer "F.Fab")
		)
		(fp_line
			(start 0.12065 -0.2794)
			(end 0.12065 -0.3048)
			(stroke
				(width 0.1)
				(type default)
			)
			(layer "F.Fab")
		)
		(fp_line
			(start 0.12065 -0.3048)
			(end 0.67945 -0.3048)
			(stroke
				(width 0.1)
				(type default)
			)
			(layer "F.Fab")
		)
		(fp_line
			(start 0.67945 -0.3048)
			(end 0.67945 0.3048)
			(stroke
				(width 0.1)
				(type default)
			)
			(layer "F.Fab")
		)
		(fp_line
			(start -0.67945 -0.305054)
			(end -0.12065 -0.305054)
			(stroke
				(width 0.1)
				(type default)
			)
			(layer "F.Fab")
		)
		(fp_line
			(start -0.12065 -0.305054)
			(end -0.12065 -0.2794)
			(stroke
				(width 0.1)
				(type default)
			)
			(layer "F.Fab")
		)
		(pad "1" smd circle
			(at -0.40005 0 270)
			(size 0 0)
			(layers "F.Cu" "F.Mask" "F.Paste")
			(net "PD_PCH_GPPC_A_18")
		)
		(pad "2" smd circle
			(at 0.40005 0 270)
			(size 0 0)
			(layers "F.Cu" "F.Mask" "F.Paste")
			(net "GND")
		)
	)
)
